# SCM (Grand Teton) — schematic netlist excerpt (pin names and nets, part order shuffled) for the footprints in the layout excerpt that follows; sources: Cadence DE-HDL packaged netlist, KiCad conversion of 12092022_DA0F0TMDCD0_F0T_Management_Board_D_brd_V3_OCP.brd

R678  Q_RES  33.2 1% EMPTY  pkg 0402LF  page 13 : A = SPI_BMC_CLK_R ; B = QSPI_2_PLD_CLK
R214  Q_RES  0 5% EMPTY  pkg 0402LF  page 15 : A = P1V8_AUX ; B = P3V3_P1V8_SD2VDD

(kicad_pcb
	(version 20260206)
	(generator "pcbnew")
	(generator_version "10.0")
	(general
		(thickness 1.6)
		(legacy_teardrops no)
	)
	(paper "A4")
	(title_block
		(title "12092022_DA0F0TMDCD0_F0T_Management_Board_D_brd_V3_OCP.brd")
		(comment 1 "Grand Teton / footprints 645-646 of 1440")
	)
	(layers
		(0 "F.Cu" signal "TOP")
		(4 "In1.Cu" signal "GND")
		(6 "In2.Cu" signal "IN1")
		(8 "In3.Cu" signal "GND1")
		(10 "In4.Cu" signal "IN2")
		(12 "In5.Cu" signal "VCC")
		(14 "In6.Cu" signal "VCC1")
		(16 "In7.Cu" signal "IN3")
		(18 "In8.Cu" signal "GND2")
		(20 "In9.Cu" signal "IN4")
		(22 "In10.Cu" signal "GND3")
		(2 "B.Cu" signal "BOTTOM")
		(9 "F.Adhes" user "F.Adhesive")
		(11 "B.Adhes" user "B.Adhesive")
		(13 "F.Paste" user "Package Geometry/Pastemask Top")
		(15 "B.Paste" user "Package Geometry/Pastemask Bottom")
		(5 "F.SilkS" user "Ref Des/Silkscreen Top")
		(7 "B.SilkS" user "Ref Des/Silkscreen Bottom")
		(1 "F.Mask" user "Board Geometry/Soldermask Top")
		(3 "B.Mask" user "Board Geometry/Soldermask Bottom")
		(17 "Dwgs.User" user "User.Drawings")
		(19 "Cmts.User" user "User.Comments")
		(21 "Eco1.User" user "User.Eco1")
		(23 "Eco2.User" user "User.Eco2")
		(25 "Edge.Cuts" user "Board Geometry/Outline")
		(27 "Margin" user)
		(31 "F.CrtYd" user "Package Geometry/Place Bound Top")
		(29 "B.CrtYd" user "Package Geometry/Place Bound Bottom")
		(35 "F.Fab" user "Ref Des/Assembly Top")
		(33 "B.Fab" user "Ref Des/Assembly Bottom")
	)
	(footprint ""
		(layer "F.Cu")
		(at 39.751 -34.036 -90)
		(property "Reference" "R214"
			(at 0 0 270)
			(layer "F.SilkS")
			(hide yes)
			(effects
				(font
					(size 1.27 1.27)
				)
			)
		)
		(property "Value" ""
			(at 0 0 270)
			(layer "F.Fab")
			(effects
				(font
					(size 1.27 1.27)
				)
			)
		)
		(duplicate_pad_numbers_are_jumpers no)
		(fp_line
			(start -0.7874 0.4064)
			(end -0.7874 -0.4064)
			(stroke
				(width 0.1524)
				(type default)
			)
			(layer "F.SilkS")
		)
		(fp_line
			(start 0.7874 0.4064)
			(end -0.7874 0.4064)
			(stroke
				(width 0.1524)
				(type default)
			)
			(layer "F.SilkS")
		)
		(fp_line
			(start -0.7874 -0.4064)
			(end 0.7874 -0.4064)
			(stroke
				(width 0.1524)
				(type default)
			)
			(layer "F.SilkS")
		)
		(fp_line
			(start 0.7874 -0.4064)
			(end 0.7874 0.4064)
			(stroke
				(width 0.1524)
				(type default)
			)
			(layer "F.SilkS")
		)
		(fp_line
			(start -0.67945 0.3048)
			(end -0.67945 -0.305054)
			(stroke
				(width 0.1)
				(type default)
			)
			(layer "F.Fab")
		)
		(fp_line
			(start -0.12065 0.3048)
			(end -0.67945 0.3048)
			(stroke
				(width 0.1)
				(type default)
			)
			(layer "F.Fab")
		)
		(fp_line
			(start 0.120396 0.3048)
			(end 0.120396 0.2794)
			(stroke
				(width 0.1)
				(type default)
			)
			(layer "F.Fab")
		)
		(fp_line
			(start 0.67945 0.3048)
			(end 0.120396 0.3048)
			(stroke
				(width 0.1)
				(type default)
			)
			(layer "F.Fab")
		)
		(fp_line
			(start -0.12065 0.2794)
			(end -0.12065 0.3048)
			(stroke
				(width 0.1)
				(type default)
			)
			(layer "F.Fab")
		)
		(fp_line
			(start 0.120396 0.2794)
			(end -0.12065 0.2794)
			(stroke
				(width 0.1)
				(type default)
			)
			(layer "F.Fab")
		)
		(fp_line
			(start -0.12065 -0.2794)
			(end 0.12065 -0.2794)
			(stroke
				(width 0.1)
				(type default)
			)
			(layer "F.Fab")
		)
		(fp_line
			(start 0.12065 -0.2794)
			(end 0.12065 -0.3048)
			(stroke
				(width 0.1)
				(type default)
			)
			(layer "F.Fab")
		)
		(fp_line
			(start 0.12065 -0.3048)
			(end 0.67945 -0.3048)
			(stroke
				(width 0.1)
				(type default)
			)
			(layer "F.Fab")
		)
		(fp_line
			(start 0.67945 -0.3048)
			(end 0.67945 0.3048)
			(stroke
				(width 0.1)
				(type default)
			)
			(layer "F.Fab")
		)
		(fp_line
			(start -0.67945 -0.305054)
			(end -0.12065 -0.305054)
			(stroke
				(width 0.1)
				(type default)
			)
			(layer "F.Fab")
		)
		(fp_line
			(start -0.12065 -0.305054)
			(end -0.12065 -0.2794)
			(stroke
				(width 0.1)
				(type default)
			)
			(layer "F.Fab")
		)
		(pad "1" smd circle
			(at -0.40005 0 270)
			(size 0 0)
			(layers "F.Cu" "F.Mask" "F.Paste")
			(net "P1V8_AUX")
		)
		(pad "2" smd circle
			(at 0.40005 0 270)
			(size 0 0)
			(layers "F.Cu" "F.Mask" "F.Paste")
			(net "P3V3_P1V8_SD2VDD")
		)
	)
	(footprint ""
		(layer "F.Cu")
		(at 53.12156 -62.2046 180)
		(property "Reference" "R678"
			(at 0 0 180)
			(layer "F.SilkS")
			(hide yes)
			(effects
				(font
					(size 1.27 1.27)
				)
			)
		)
		(property "Value" ""
			(at 0 0 180)
			(layer "F.Fab")
			(effects
				(font
					(size 1.27 1.27)
				)
			)
		)
		(duplicate_pad_numbers_are_jumpers no)
		(fp_line
			(start 0.7874 0.4064)
			(end -0.7874 0.4064)
			(stroke
				(width 0.1524)
				(type default)
			)
			(layer "F.SilkS")
		)
		(fp_line
			(start 0.7874 -0.4064)
			(end 0.7874 0.4064)
			(stroke
				(width 0.1524)
				(type default)
			)
			(layer "F.SilkS")
		)
		(fp_line
			(start -0.7874 0.4064)
			(end -0.7874 -0.4064)
			(stroke
				(width 0.1524)
				(type default)
			)
			(layer "F.SilkS")
		)
		(fp_line
			(start -0.7874 -0.4064)
			(end 0.7874 -0.4064)
			(stroke
				(width 0.1524)
				(type default)
			)
			(layer "F.SilkS")
		)
		(fp_line
			(start 0.67945 0.3048)
			(end 0.120396 0.3048)
			(stroke
				(width 0.1)
				(type default)
			)
			(layer "F.Fab")
		)
		(fp_line
			(start 0.67945 -0.3048)
			(end 0.67945 0.3048)
			(stroke
				(width 0.1)
				(type default)
			)
			(layer "F.Fab")
		)
		(fp_line
			(start 0.12065 -0.2794)
			(end 0.12065 -0.3048)
			(stroke
				(width 0.1)
				(type default)
			)
			(layer "F.Fab")
		)
		(fp_line
			(start 0.12065 -0.3048)
			(end 0.67945 -0.3048)
			(stroke
				(width 0.1)
				(type default)
			)
			(layer "F.Fab")
		)
		(fp_line
			(start 0.120396 0.3048)
			(end 0.120396 0.2794)
			(stroke
				(width 0.1)
				(type default)
			)
			(layer "F.Fab")
		)
		(fp_line
			(start 0.120396 0.2794)
			(end -0.12065 0.2794)
			(stroke
				(width 0.1)
				(type default)
			)
			(layer "F.Fab")
		)
		(fp_line
			(start -0.12065 0.3048)
			(end -0.67945 0.3048)
			(stroke
				(width 0.1)
				(type default)
			)
			(layer "F.Fab")
		)
		(fp_line
			(start -0.12065 0.2794)
			(end -0.12065 0.3048)
			(stroke
				(width 0.1)
				(type default)
			)
			(layer "F.Fab")
		)
		(fp_line
			(start -0.12065 -0.2794)
			(end 0.12065 -0.2794)
			(stroke
				(width 0.1)
				(type default)
			)
			(layer "F.Fab")
		)
		(fp_line
			(start -0.12065 -0.305054)
			(end -0.12065 -0.2794)
			(stroke
				(width 0.1)
				(type default)
			)
			(layer "F.Fab")
		)
		(fp_line
			(start -0.67945 0.3048)
			(end -0.67945 -0.305054)
			(stroke
				(width 0.1)
				(type default)
			)
			(layer "F.Fab")
		)
		(fp_line
			(start -0.67945 -0.305054)
			(end -0.12065 -0.305054)
			(stroke
				(width 0.1)
				(type default)
			)
			(layer "F.Fab")
		)
		(pad "1" smd circle
			(at -0.40005 0 180)
			(size 0 0)
			(layers "F.Cu" "F.Mask" "F.Paste")
			(net "SPI_BMC_CLK_R")
		)
		(pad "2" smd circle
			(at 0.40005 0 180)
			(size 0 0)
			(layers "F.Cu" "F.Mask" "F.Paste")
			(net "QSPI_2_PLD_CLK")
		)
	)
)
